(kicad_pcb
	(version 20260206)
	(generator "pcbnew")
	(generator_version "10.0")
	(general
		(thickness 1.6)
		(legacy_teardrops no)
	)
	(paper "A4")
	(title_block
		(title "9052_F0T_PDB_Converter_Brick_F_V03_1208_1600_OCP.brd")
		(comment 1 "Grand Teton / footprint 28 of 578 (J1), pads 1-62 of 62")
	)
	(layers
		(0 "F.Cu" signal "TOP")
		(4 "In1.Cu" signal "GND")
		(6 "In2.Cu" signal "IN1")
		(8 "In3.Cu" signal "GND1")
		(10 "In4.Cu" signal "VCC")
		(12 "In5.Cu" signal "VCC1")
		(14 "In6.Cu" signal "GND2")
		(16 "In7.Cu" signal "IN2")
		(18 "In8.Cu" signal "GND3")
		(2 "B.Cu" signal "BOTTOM")
		(9 "F.Adhes" user "F.Adhesive")
		(11 "B.Adhes" user "B.Adhesive")
		(13 "F.Paste" user "Package Geometry/Pastemask Top")
		(15 "B.Paste" user "Package Geometry/Pastemask Bottom")
		(5 "F.SilkS" user "Ref Des/Silkscreen Top")
		(7 "B.SilkS" user "Ref Des/Silkscreen Bottom")
		(1 "F.Mask" user "Board Geometry/Soldermask Top")
		(3 "B.Mask" user "Board Geometry/Soldermask Bottom")
		(17 "Dwgs.User" user "User.Drawings")
		(19 "Cmts.User" user "User.Comments")
		(21 "Eco1.User" user "User.Eco1")
		(23 "Eco2.User" user "User.Eco2")
		(25 "Edge.Cuts" user "Board Geometry/Outline")
		(27 "Margin" user)
		(31 "F.CrtYd" user "Package Geometry/Place Bound Top")
		(29 "B.CrtYd" user "Package Geometry/Place Bound Bottom")
		(35 "F.Fab" user "Ref Des/Assembly Top")
		(33 "B.Fab" user "Ref Des/Assembly Bottom")
	)
	(footprint ""
		(layer "F.Cu")
		(at 211.469986 -37.949632 -90)
		(property "Reference" "J1"
			(at -7.489698 -41.895014 0)
			(unlocked yes)
			(layer "F.SilkS")
			(effects
				(font
					(size 0.7874 0.5842)
					(thickness 0.1524)
				)
				(justify left)
			)
		)
		(property "Value" ""
			(at 0 0 270)
			(layer "F.Fab")
			(effects
				(font
					(size 1.27 1.27)
				)
			)
		)
		(duplicate_pad_numbers_are_jumpers no)
		(pad "" np_thru_hole circle
			(at 0 -37.465 270)
			(size 0 0)
			(drill 3.2004)
			(layers "*.Cu" "*.Mask")
			(clearance 0)
		)
		(pad "" np_thru_hole circle
			(at 0 42.545 270)
			(size 0 0)
			(drill 3.2004)
			(layers "*.Cu" "*.Mask")
			(clearance 0)
		)
		(pad "A1" thru_hole rect
			(at 0 0 270)
			(size 1.52781 1.52781)
			(drill 1.01981)
			(layers "*.Cu" "*.Mask")
			(remove_unused_layers no)
			(net "TP_J1_A1")
			(clearance 0)
			(padstack
				(mode front_inner_back)
				(layer "Inner"
					(shape circle)
					(size 1.52781 1.52781)
					(clearance 0)
				)
				(layer "B.Cu"
					(shape rect)
					(size 1.52781 1.52781)
					(clearance 0)
				)
			)
		)
		(pad "A2" thru_hole circle
			(at 0 2.54 270)
			(size 1.52781 1.52781)
			(drill 1.01981)
			(layers "*.Cu" "*.Mask")
			(remove_unused_layers no)
			(net "FM_AC_PWR_CYCLE_R_N")
			(clearance 0)
		)
		(pad "A3" thru_hole circle
			(at 0 5.08 270)
			(size 1.52781 1.52781)
			(drill 1.01981)
			(layers "*.Cu" "*.Mask")
			(remove_unused_layers no)
			(net "P3V3_AUX_SCALED")
			(clearance 0)
		)
		(pad "B1" thru_hole circle
			(at 2.54 0 270)
			(size 1.52781 1.52781)
			(drill 1.01981)
			(layers "*.Cu" "*.Mask")
			(remove_unused_layers no)
			(net "RST_SMB_PDB_R_N")
			(clearance 0)
		)
		(pad "B2" thru_hole circle
			(at 2.54 2.54 270)
			(size 1.52781 1.52781)
			(drill 1.01981)
			(layers "*.Cu" "*.Mask")
			(remove_unused_layers no)
			(net "PWRGD_P3V3_AUX_MB_R")
			(clearance 0)
		)
		(pad "B3" thru_hole circle
			(at 2.54 5.08 270)
			(size 1.52781 1.52781)
			(drill 1.01981)
			(layers "*.Cu" "*.Mask")
			(remove_unused_layers no)
			(net "GND")
			(clearance 0)
		)
		(pad "C1" thru_hole circle
			(at 5.08 0 270)
			(size 1.52781 1.52781)
			(drill 1.01981)
			(layers "*.Cu" "*.Mask")
			(remove_unused_layers no)
			(net "SMB_MB_PDB_R_SCL")
			(clearance 0)
		)
		(pad "C2" thru_hole circle
			(at 5.08 2.54 270)
			(size 1.52781 1.52781)
			(drill 1.01981)
			(layers "*.Cu" "*.Mask")
			(remove_unused_layers no)
			(net "SMB_MB_PDB_R_SDA")
			(clearance 0)
		)
		(pad "C3" thru_hole circle
			(at 5.08 5.08 270)
			(size 1.52781 1.52781)
			(drill 1.01981)
			(layers "*.Cu" "*.Mask")
			(remove_unused_layers no)
			(net "PWRGD_GPU_HSC_BUF_R")
			(clearance 0)
		)
		(pad "D1" thru_hole circle
			(at 7.62 0 270)
			(size 1.52781 1.52781)
			(drill 1.01981)
			(layers "*.Cu" "*.Mask")
			(remove_unused_layers no)
			(net "FAN_PWR_R_EN")
			(clearance 0)
		)
		(pad "D2" thru_hole circle
			(at 7.62 2.54 270)
			(size 1.52781 1.52781)
			(drill 1.01981)
			(layers "*.Cu" "*.Mask")
			(remove_unused_layers no)
			(net "GPU_HSC_R_EN")
			(clearance 0)
		)
		(pad "D3" thru_hole circle
			(at 7.62 5.08 270)
			(size 1.52781 1.52781)
			(drill 1.01981)
			(layers "*.Cu" "*.Mask")
			(remove_unused_layers no)
			(net "P12V_BRICK_PWRGD_R_N")
			(clearance 0)
		)
		(pad "P1_1" thru_hole circle
			(at 7.62 -25.4 270)
			(size 1.52781 1.52781)
			(drill 1.01981)
			(layers "*.Cu" "*.Mask")
			(remove_unused_layers no)
			(net "GND")
			(clearance 0)
		)
		(pad "P1_2" thru_hole circle
			(at 5.08 -25.4 270)
			(size 1.52781 1.52781)
			(drill 1.01981)
			(layers "*.Cu" "*.Mask")
			(remove_unused_layers no)
			(net "GND")
			(clearance 0)
		)
		(pad "P1_3" thru_hole circle
			(at 2.54 -25.4 270)
			(size 1.52781 1.52781)
			(drill 1.01981)
			(layers "*.Cu" "*.Mask")
			(remove_unused_layers no)
			(net "GND")
			(clearance 0)
		)
		(pad "P1_4" thru_hole circle
			(at 0 -25.4 270)
			(size 1.52781 1.52781)
			(drill 1.01981)
			(layers "*.Cu" "*.Mask")
			(remove_unused_layers no)
			(net "GND")
			(clearance 0)
		)
		(pad "P1_5" thru_hole circle
			(at 7.62 -22.86 270)
			(size 1.52781 1.52781)
			(drill 1.01981)
			(layers "*.Cu" "*.Mask")
			(remove_unused_layers no)
			(net "GND")
			(clearance 0)
		)
		(pad "P1_6" thru_hole circle
			(at 5.08 -22.86 270)
			(size 1.52781 1.52781)
			(drill 1.01981)
			(layers "*.Cu" "*.Mask")
			(remove_unused_layers no)
			(net "GND")
			(clearance 0)
		)
		(pad "P1_7" thru_hole circle
			(at 2.54 -22.86 270)
			(size 1.52781 1.52781)
			(drill 1.01981)
			(layers "*.Cu" "*.Mask")
			(remove_unused_layers no)
			(net "GND")
			(clearance 0)
		)
		(pad "P1_8" thru_hole circle
			(at 0 -22.86 270)
			(size 1.52781 1.52781)
			(drill 1.01981)
			(layers "*.Cu" "*.Mask")
			(remove_unused_layers no)
			(net "GND")
			(clearance 0)
		)
		(pad "P2_1" thru_hole circle
			(at 7.62 -16.51 270)
			(size 1.52781 1.52781)
			(drill 1.01981)
			(layers "*.Cu" "*.Mask")
			(remove_unused_layers no)
			(net "GND")
			(clearance 0)
		)
		(pad "P2_2" thru_hole circle
			(at 5.08 -16.51 270)
			(size 1.52781 1.52781)
			(drill 1.01981)
			(layers "*.Cu" "*.Mask")
			(remove_unused_layers no)
			(net "GND")
			(clearance 0)
		)
		(pad "P2_3" thru_hole circle
			(at 2.54 -16.51 270)
			(size 1.52781 1.52781)
			(drill 1.01981)
			(layers "*.Cu" "*.Mask")
			(remove_unused_layers no)
			(net "GND")
			(clearance 0)
		)
		(pad "P2_4" thru_hole circle
			(at 0 -16.51 270)
			(size 1.52781 1.52781)
			(drill 1.01981)
			(layers "*.Cu" "*.Mask")
			(remove_unused_layers no)
			(net "GND")
			(clearance 0)
		)
		(pad "P2_5" thru_hole circle
			(at 7.62 -13.97 270)
			(size 1.52781 1.52781)
			(drill 1.01981)
			(layers "*.Cu" "*.Mask")
			(remove_unused_layers no)
			(net "GND")
			(clearance 0)
		)
		(pad "P2_6" thru_hole circle
			(at 5.08 -13.97 270)
			(size 1.52781 1.52781)
			(drill 1.01981)
			(layers "*.Cu" "*.Mask")
			(remove_unused_layers no)
			(net "GND")
			(clearance 0)
		)
		(pad "P2_7" thru_hole circle
			(at 2.54 -13.97 270)
			(size 1.52781 1.52781)
			(drill 1.01981)
			(layers "*.Cu" "*.Mask")
			(remove_unused_layers no)
			(net "GND")
			(clearance 0)
		)
		(pad "P2_8" thru_hole circle
			(at 0 -13.97 270)
			(size 1.52781 1.52781)
			(drill 1.01981)
			(layers "*.Cu" "*.Mask")
			(remove_unused_layers no)
			(net "GND")
			(clearance 0)
		)
		(pad "P3_1" thru_hole circle
			(at 7.62 -7.62 270)
			(size 1.52781 1.52781)
			(drill 1.01981)
			(layers "*.Cu" "*.Mask")
			(remove_unused_layers no)
			(net "GND")
			(clearance 0)
		)
		(pad "P3_2" thru_hole circle
			(at 5.08 -7.62 270)
			(size 1.52781 1.52781)
			(drill 1.01981)
			(layers "*.Cu" "*.Mask")
			(remove_unused_layers no)
			(net "GND")
			(clearance 0)
		)
		(pad "P3_3" thru_hole circle
			(at 2.54 -7.62 270)
			(size 1.52781 1.52781)
			(drill 1.01981)
			(layers "*.Cu" "*.Mask")
			(remove_unused_layers no)
			(net "GND")
			(clearance 0)
		)
		(pad "P3_4" thru_hole circle
			(at 0 -7.62 270)
			(size 1.52781 1.52781)
			(drill 1.01981)
			(layers "*.Cu" "*.Mask")
			(remove_unused_layers no)
			(net "GND")
			(clearance 0)
		)
		(pad "P3_5" thru_hole circle
			(at 7.62 -5.08 270)
			(size 1.52781 1.52781)
			(drill 1.01981)
			(layers "*.Cu" "*.Mask")
			(remove_unused_layers no)
			(net "GND")
			(clearance 0)
		)
		(pad "P3_6" thru_hole circle
			(at 5.08 -5.08 270)
			(size 1.52781 1.52781)
			(drill 1.01981)
			(layers "*.Cu" "*.Mask")
			(remove_unused_layers no)
			(net "GND")
			(clearance 0)
		)
		(pad "P3_7" thru_hole circle
			(at 2.54 -5.08 270)
			(size 1.52781 1.52781)
			(drill 1.01981)
			(layers "*.Cu" "*.Mask")
			(remove_unused_layers no)
			(net "GND")
			(clearance 0)
		)
		(pad "P3_8" thru_hole circle
			(at 0 -5.08 270)
			(size 1.52781 1.52781)
			(drill 1.01981)
			(layers "*.Cu" "*.Mask")
			(remove_unused_layers no)
			(net "GND")
			(clearance 0)
		)
		(pad "P4_1" thru_hole circle
			(at 7.62 10.16 270)
			(size 1.52781 1.52781)
			(drill 1.01981)
			(layers "*.Cu" "*.Mask")
			(remove_unused_layers no)
			(net "P12V_BRICK")
			(clearance 0)
		)
		(pad "P4_2" thru_hole circle
			(at 5.08 10.16 270)
			(size 1.52781 1.52781)
			(drill 1.01981)
			(layers "*.Cu" "*.Mask")
			(remove_unused_layers no)
			(net "P12V_BRICK")
			(clearance 0)
		)
		(pad "P4_3" thru_hole circle
			(at 2.54 10.16 270)
			(size 1.52781 1.52781)
			(drill 1.01981)
			(layers "*.Cu" "*.Mask")
			(remove_unused_layers no)
			(net "P12V_BRICK")
			(clearance 0)
		)
		(pad "P4_4" thru_hole circle
			(at 0 10.16 270)
			(size 1.52781 1.52781)
			(drill 1.01981)
			(layers "*.Cu" "*.Mask")
			(remove_unused_layers no)
			(net "P12V_BRICK")
			(clearance 0)
		)
		(pad "P4_5" thru_hole circle
			(at 7.62 12.7 270)
			(size 1.52781 1.52781)
			(drill 1.01981)
			(layers "*.Cu" "*.Mask")
			(remove_unused_layers no)
			(net "P12V_BRICK")
			(clearance 0)
		)
		(pad "P4_6" thru_hole circle
			(at 5.08 12.7 270)
			(size 1.52781 1.52781)
			(drill 1.01981)
			(layers "*.Cu" "*.Mask")
			(remove_unused_layers no)
			(net "P12V_BRICK")
			(clearance 0)
		)
		(pad "P4_7" thru_hole circle
			(at 2.54 12.7 270)
			(size 1.52781 1.52781)
			(drill 1.01981)
			(layers "*.Cu" "*.Mask")
			(remove_unused_layers no)
			(net "P12V_BRICK")
			(clearance 0)
		)
		(pad "P4_8" thru_hole circle
			(at 0 12.7 270)
			(size 1.52781 1.52781)
			(drill 1.01981)
			(layers "*.Cu" "*.Mask")
			(remove_unused_layers no)
			(net "P12V_BRICK")
			(clearance 0)
		)
		(pad "P5_1" thru_hole circle
			(at 7.62 19.05 270)
			(size 1.52781 1.52781)
			(drill 1.01981)
			(layers "*.Cu" "*.Mask")
			(remove_unused_layers no)
			(net "P12V_BRICK")
			(clearance 0)
		)
		(pad "P5_2" thru_hole circle
			(at 5.08 19.05 270)
			(size 1.52781 1.52781)
			(drill 1.01981)
			(layers "*.Cu" "*.Mask")
			(remove_unused_layers no)
			(net "P12V_BRICK")
			(clearance 0)
		)
		(pad "P5_3" thru_hole circle
			(at 2.54 19.05 270)
			(size 1.52781 1.52781)
			(drill 1.01981)
			(layers "*.Cu" "*.Mask")
			(remove_unused_layers no)
			(net "P12V_BRICK")
			(clearance 0)
		)
		(pad "P5_4" thru_hole circle
			(at 0 19.05 270)
			(size 1.52781 1.52781)
			(drill 1.01981)
			(layers "*.Cu" "*.Mask")
			(remove_unused_layers no)
			(net "P12V_BRICK")
			(clearance 0)
		)
		(pad "P5_5" thru_hole circle
			(at 7.62 21.59 270)
			(size 1.52781 1.52781)
			(drill 1.01981)
			(layers "*.Cu" "*.Mask")
			(remove_unused_layers no)
			(net "P12V_BRICK")
			(clearance 0)
		)
		(pad "P5_6" thru_hole circle
			(at 5.08 21.59 270)
			(size 1.52781 1.52781)
			(drill 1.01981)
			(layers "*.Cu" "*.Mask")
			(remove_unused_layers no)
			(net "P12V_BRICK")
			(clearance 0)
		)
		(pad "P5_7" thru_hole circle
			(at 2.54 21.59 270)
			(size 1.52781 1.52781)
			(drill 1.01981)
			(layers "*.Cu" "*.Mask")
			(remove_unused_layers no)
			(net "P12V_BRICK")
			(clearance 0)
		)
		(pad "P5_8" thru_hole circle
			(at 0 21.59 270)
			(size 1.52781 1.52781)
			(drill 1.01981)
			(layers "*.Cu" "*.Mask")
			(remove_unused_layers no)
			(net "P12V_BRICK")
			(clearance 0)
		)
		(pad "P6_1" thru_hole circle
			(at 7.62 27.94 270)
			(size 1.52781 1.52781)
			(drill 1.01981)
			(layers "*.Cu" "*.Mask")
			(remove_unused_layers no)
			(net "P12V_BRICK")
			(clearance 0)
		)
		(pad "P6_2" thru_hole circle
			(at 5.08 27.94 270)
			(size 1.52781 1.52781)
			(drill 1.01981)
			(layers "*.Cu" "*.Mask")
			(remove_unused_layers no)
			(net "P12V_BRICK")
			(clearance 0)
		)
		(pad "P6_3" thru_hole circle
			(at 2.54 27.94 270)
			(size 1.52781 1.52781)
			(drill 1.01981)
			(layers "*.Cu" "*.Mask")
			(remove_unused_layers no)
			(net "P12V_BRICK")
			(clearance 0)
		)
		(pad "P6_4" thru_hole circle
			(at 0 27.94 270)
			(size 1.52781 1.52781)
			(drill 1.01981)
			(layers "*.Cu" "*.Mask")
			(remove_unused_layers no)
			(net "P12V_BRICK")
			(clearance 0)
		)
		(pad "P6_5" thru_hole circle
			(at 7.62 30.48 270)
			(size 1.52781 1.52781)
			(drill 1.01981)
			(layers "*.Cu" "*.Mask")
			(remove_unused_layers no)
			(net "P12V_BRICK")
			(clearance 0)
		)
		(pad "P6_6" thru_hole circle
			(at 5.08 30.48 270)
			(size 1.52781 1.52781)
			(drill 1.01981)
			(layers "*.Cu" "*.Mask")
			(remove_unused_layers no)
			(net "P12V_BRICK")
			(clearance 0)
		)
		(pad "P6_7" thru_hole circle
			(at 2.54 30.48 270)
			(size 1.52781 1.52781)
			(drill 1.01981)
			(layers "*.Cu" "*.Mask")
			(remove_unused_layers no)
			(net "P12V_BRICK")
			(clearance 0)
		)
		(pad "P6_8" thru_hole circle
			(at 0 30.48 270)
			(size 1.52781 1.52781)
			(drill 1.01981)
			(layers "*.Cu" "*.Mask")
			(remove_unused_layers no)
			(net "P12V_BRICK")
			(clearance 0)
		)
	)
)
